FILE_TYPE = CONNECTIVITY;
{Allegro Design Entry HDL 16.6-p007 (v16-6-112F) 10/10/2012}
"PAGE_NUMBER" = 150;
0"NC";
1"GND\g";
2"P1V2_AUX_BMC\g";
3"GND\g";
4"VCC_D_PLL_3V3\g";
5"GND\g";
6"GND\g";
7"VCC_VA_3V3\g";
8"GND\g";
9"P3V3_USB2A_ALG\g";
10"P1V15_AUX_BMC\g";
11"P3V3_STBY\g";
12"P3V3_STBY\g";
13"P3V3_STBY\g";
14"VCC_DACAV3V3\g";
15"GND\g";
16"P3V3_STBY\g";
17"VCC_ADCAV3V3\g";
18"GND\g";
19"GND\g";
20"GND\g";
21"VCC_D_3V3\g";
22"GND\g";
23"VCC_PA_3V3\g";
24"GND\g";
25"P3V3_STBY\g";
26"GND\g";
27"P1V15_AUX_BMC\g";
28"P3V3_STBY\g";
29"P3V3_STBY\g";
30"P3V3_STBY\g";
31"P3V3_STBY\g";
32"VCC_A_1V1\g";
%"CAP"
"1","(-2750,1300)","0","mstr_discrete","I1";
;
CDS_SEC"1"
$SEC"1"
CDS_LOCATION"C25W60"
BOM_COST"SM_CONTROLLER"
ROOM"BMC"
CDS_LIB"mstr_discrete"
PACK_TYPE"0402"
MATERIAL"X6S"
TOLERANCE"10%"
VOLTAGE"6.3V"
VALUE"1.0UF"
LOCATION"C25W60"
PART_NUMBER"D97712-004";
"A"
$PN"1"25;
"B"
$PN"2"24;
%"SCD1U16V2KX-3GP"
"1","(775,2500)","0","w_hdl","I10";
;
CDS_SEC"1"
$SEC"1"
CDS_LOCATION"C25W55"
PART_NUMBER"78.10421.2FL"
PACK_TYPE"SMD-BCG"
CDS_LMAN_SYM_OUTLINE"-50,25,50,-25"
CDS_LIB"w_hdl"
LOCATION"C25W55"
VALUE"SCD1U16V2KX-3GP";
"2"
$PN"2"1;
"1"
$PN"1"2;
%"GND"
"1","(775,2075)","0","mstr_symbols","I11";
;
CDS_LIB"mstr_symbols"
HDL_POWER"GND"
SIZE"1B"
BODY_TYPE"PLUMBING"
VOLTAGE"0.0V";
"A\NAC"1;
%"CAP"
"1","(525,2475)","0","mstr_discrete","I12";
;
CDS_SEC"1"
$SEC"1"
CDS_LOCATION"C25W54"
CDS_LIB"mstr_discrete"
BOM_COST"SM_CONTROLLER"
ROOM"BMC"
LOCATION"C25W54"
PACK_TYPE"0402"
VOLTAGE"6.3V"
PART_NUMBER"D97712-004"
TOLERANCE"10%"
MATERIAL"X6S"
VALUE"1.0UF";
"A"
$PN"1"2;
"B"
$PN"2"1;
%"CAP"
"1","(275,2475)","0","mstr_discrete","I13";
;
CDS_SEC"1"
$SEC"1"
CDS_LOCATION"C25W53"
CDS_LIB"mstr_discrete"
BOM_COST"SM_CONTROLLER"
ROOM"BMC"
PACK_TYPE"0402"
PART_NUMBER"D97712-004"
MATERIAL"X6S"
TOLERANCE"10%"
VALUE"1.0UF"
LOCATION"C25W53"
VOLTAGE"6.3V";
"A"
$PN"1"2;
"B"
$PN"2"1;
%"CAP"
"1","(25,2475)","0","mstr_discrete","I14";
;
CDS_SEC"1"
$SEC"1"
CDS_LOCATION"C25W52"
ROOM"BMC"
BOM_COST"SM_CONTROLLER"
CDS_LIB"mstr_discrete"
PART_NUMBER"D97712-004"
TOLERANCE"10%"
MATERIAL"X6S"
PACK_TYPE"0402"
VOLTAGE"6.3V"
VALUE"1.0UF"
LOCATION"C25W52";
"A"
$PN"1"2;
"B"
$PN"2"1;
%"W_VCC_CIRCLE"
"1","(-275,2925)","0","w_power","I15";
;
CDS_LIB"w_power"
CDS_LMAN_SYM_OUTLINE"-100,100,100,-100"
BODY_TYPE"PLUMBING"
HDL_POWER"P1V2_AUX_BMC";
"VCC_CIRCLE \B"2;
%"GND"
"1","(-500,3175)","0","mstr_symbols","I16";
;
HDL_POWER"GND"
SIZE"1B"
CDS_LIB"mstr_symbols"
BODY_TYPE"PLUMBING"
VOLTAGE"0.0V";
"A\NAC"3;
%"SC4D7U10V3KX-GP"
"1","(-500,3550)","0","w_hdl","I17";
;
CDS_SEC"1"
$SEC"1"
CDS_LOCATION"C25W39"
PART_NUMBER"78.47523.5BL"
PACK_TYPE"SMD-BCG"
CDS_LIB"w_hdl"
CDS_LMAN_SYM_OUTLINE"-50,25,50,-25"
VALUE"SC4D7U10V3KX-GP"
LOCATION"C25W39";
"2"
$PN"2"3;
"1"
$PN"1"32;
%"SCD1U16V2KX-3GP"
"1","(-900,3550)","0","w_hdl","I18";
;
CDS_SEC"1"
$SEC"1"
CDS_LOCATION"C25W38"
PART_NUMBER"78.10421.2FL"
PACK_TYPE"SMD-BCG"
CDS_LMAN_SYM_OUTLINE"-50,25,50,-25"
CDS_LIB"w_hdl"
LOCATION"C25W38"
VALUE"SCD1U16V2KX-3GP";
"2"
$PN"2"3;
"1"
$PN"1"32;
%"CAP"
"1","(-275,2475)","0","mstr_discrete","I19";
;
CDS_SEC"1"
$SEC"1"
CDS_LOCATION"C25W51"
BOM_COST"SM_CONTROLLER"
ROOM"BMC"
CDS_LIB"mstr_discrete"
LOCATION"C25W51"
MATERIAL"X6S"
PACK_TYPE"0402"
PART_NUMBER"D97712-004"
VALUE"1.0UF"
VOLTAGE"6.3V"
TOLERANCE"10%";
"A"
$PN"1"2;
"B"
$PN"2"1;
%"SC4D7U10V3KX-GP"
"1","(650,1450)","0","w_hdl","I2";
;
CDS_SEC"1"
$SEC"1"
CDS_LOCATION"C25W65"
CDS_LIB"w_hdl"
CDS_LMAN_SYM_OUTLINE"-50,25,50,-25"
PART_NUMBER"78.47523.5BL"
PACK_TYPE"SMD-BCG"
LOCATION"C25W65"
VALUE"SC4D7U10V3KX-GP";
"2"
$PN"2"6;
"1"
$PN"1"4;
%"W_VCC_CIRCLE"
"1","(-300,1925)","0","w_power","I20";
;
CDS_LIB"w_power"
CDS_LMAN_SYM_OUTLINE"-100,100,100,-100"
BODY_TYPE"PLUMBING"
HDL_POWER"VCC_D_PLL_3V3";
"VCC_CIRCLE \B"4;
%"SC4D7U10V3KX-GP"
"1","(-950,2575)","0","w_hdl","I21";
;
CDS_SEC"1"
$SEC"1"
CDS_LOCATION"C25W50"
CDS_LIB"w_hdl"
CDS_LMAN_SYM_OUTLINE"-50,25,50,-25"
PACK_TYPE"SMD-BCG"
PART_NUMBER"78.47523.5BL"
VALUE"SC4D7U10V3KX-GP"
LOCATION"C25W50";
"2"
$PN"2"5;
"1"
$PN"1"12;
%"GND"
"1","(-950,2200)","0","mstr_symbols","I22";
;
CDS_LIB"mstr_symbols"
SIZE"1B"
HDL_POWER"GND"
BODY_TYPE"PLUMBING"
VOLTAGE"0.0V";
"A\NAC"5;
%"GND"
"1","(650,975)","0","mstr_symbols","I23";
;
CDS_LIB"mstr_symbols"
SIZE"1B"
HDL_POWER"GND"
BODY_TYPE"PLUMBING"
VOLTAGE"0.0V";
"A\NAC"6;
%"SCD1U16V2KX-3GP"
"1","(250,1450)","0","w_hdl","I24";
;
CDS_SEC"1"
$SEC"1"
CDS_LOCATION"C25W64"
CDS_LIB"w_hdl"
CDS_LMAN_SYM_OUTLINE"-50,25,50,-25"
PACK_TYPE"SMD-BCG"
PART_NUMBER"78.10421.2FL"
VALUE"SCD1U16V2KX-3GP"
LOCATION"C25W64";
"2"
$PN"2"6;
"1"
$PN"1"4;
%"CAP"
"1","(-300,1425)","0","mstr_discrete","I25";
;
CDS_SEC"1"
$SEC"1"
CDS_LOCATION"C25W63"
CDS_LIB"mstr_discrete"
BOM_COST"SM_CONTROLLER"
ROOM"BMC"
MATERIAL"X6S"
PACK_TYPE"0402"
LOCATION"C25W63"
VALUE"1.0UF"
PART_NUMBER"D97712-004"
TOLERANCE"10%"
VOLTAGE"6.3V";
"A"
$PN"1"4;
"B"
$PN"2"6;
%"HCB1608KF-800T30-GP"
"1","(-850,1775)","1","w_hdl","I26";
;
CDS_SEC"1"
$SEC"1"
CDS_LOCATION"FB2T6"
PACK_TYPE"DISCRET-G9"
PART_NUMBER"68.00230.231"
CDS_LMAN_SYM_OUTLINE"-50,100,50,-100"
CDS_LIB"w_hdl"
VALUE"HCB1608KF-800T30-GP"
LOCATION"FB2T6";
"2"
$PN"2"4;
"1"
$PN"1"11;
%"W_VCC_CIRCLE"
"1","(-1125,5225)","0","w_power","I27";
;
CDS_LMAN_SYM_OUTLINE"-100,100,100,-100"
CDS_LIB"w_power"
BODY_TYPE"PLUMBING"
HDL_POWER"VCC_VA_3V3";
"VCC_CIRCLE \B"7;
%"SC4D7U10V3KX-GP"
"1","(-1125,4750)","0","w_hdl","I28";
;
CDS_SEC"1"
$SEC"1"
CDS_LOCATION"C25W69"
CDS_LMAN_SYM_OUTLINE"-50,25,50,-25"
CDS_LIB"w_hdl"
PART_NUMBER"78.47523.5BL"
PACK_TYPE"SMD-BCG"
LOCATION"C25W69"
VALUE"SC4D7U10V3KX-GP";
"2"
$PN"2"8;
"1"
$PN"1"7;
%"GND"
"1","(-1125,4275)","0","mstr_symbols","I29";
;
VOLTAGE"0.0V"
BODY_TYPE"PLUMBING"
CDS_LIB"mstr_symbols"
SIZE"1B"
HDL_POWER"GND";
"A\NAC"8;
%"W_VCC_CIRCLE"
"1","(575,5175)","0","w_power","I3";
;
CDS_LIB"w_power"
CDS_LMAN_SYM_OUTLINE"-100,100,100,-100"
BODY_TYPE"PLUMBING"
HDL_POWER"P3V3_USB2A_ALG";
"VCC_CIRCLE \B"9;
%"SCD1U16V2KX-3GP"
"1","(-1525,4750)","0","w_hdl","I30";
;
CDS_SEC"1"
$SEC"1"
CDS_LOCATION"C25W68"
CDS_LMAN_SYM_OUTLINE"-50,25,50,-25"
CDS_LIB"w_hdl"
PACK_TYPE"SMD-BCG"
PART_NUMBER"78.10421.2FL"
VALUE"SCD1U16V2KX-3GP"
LOCATION"C25W68";
"2"
$PN"2"8;
"1"
$PN"1"7;
%"CAP"
"1","(-1825,4725)","0","mstr_discrete","I31";
;
CDS_SEC"1"
$SEC"1"
CDS_LOCATION"C25W67"
CDS_LIB"mstr_discrete"
BOM_COST"SM_CONTROLLER"
ROOM"BMC"
PACK_TYPE"0402"
PART_NUMBER"D97712-004"
MATERIAL"X6S"
TOLERANCE"10%"
VOLTAGE"6.3V"
VALUE"1.0UF"
LOCATION"C25W67";
"A"
$PN"1"7;
"B"
$PN"2"8;
%"HCB1608KF-800T30-GP"
"1","(-2725,5075)","1","w_hdl","I32";
;
CDS_SEC"1"
$SEC"1"
CDS_LOCATION"FB2T1"
CDS_LIB"w_hdl"
CDS_LMAN_SYM_OUTLINE"-50,100,50,-100"
PART_NUMBER"68.00230.231"
PACK_TYPE"DISCRET-G9"
LOCATION"FB2T1"
VALUE"HCB1608KF-800T30-GP";
"2"
$PN"2"7;
"1"
$PN"1"13;
%"CAP"
"1","(-2075,4725)","0","mstr_discrete","I33";
;
CDS_SEC"1"
$SEC"1"
CDS_LOCATION"C25W66"
CDS_LIB"mstr_discrete"
BOM_COST"SM_CONTROLLER"
ROOM"BMC"
PART_NUMBER"D97712-004"
PACK_TYPE"0402"
MATERIAL"X6S"
VALUE"1.0UF"
TOLERANCE"10%"
VOLTAGE"6.3V"
LOCATION"C25W66";
"A"
$PN"1"7;
"B"
$PN"2"8;
%"W_VCC_CIRCLE"
"1","(-2200,3975)","0","w_power","I34";
;
BODY_TYPE"PLUMBING"
CDS_LMAN_SYM_OUTLINE"-100,100,100,-100"
CDS_LIB"w_power"
HDL_POWER"P1V15_AUX_BMC";
"VCC_CIRCLE \B"10;
%"CAP"
"1","(-1450,3525)","0","mstr_discrete","I35";
;
CDS_SEC"1"
$SEC"1"
CDS_LOCATION"C25W37"
ROOM"BMC"
BOM_COST"SM_CONTROLLER"
CDS_LIB"mstr_discrete"
LOCATION"C25W37"
VALUE"1.0UF"
PART_NUMBER"D97712-004"
PACK_TYPE"0402"
MATERIAL"X6S"
TOLERANCE"10%"
VOLTAGE"6.3V";
"A"
$PN"1"32;
"B"
$PN"2"3;
%"SCD1U16V2KX-3GP"
"1","(-1350,2575)","0","w_hdl","I36";
;
CDS_SEC"1"
$SEC"1"
CDS_LOCATION"C25W49"
CDS_LIB"w_hdl"
CDS_LMAN_SYM_OUTLINE"-50,25,50,-25"
PACK_TYPE"SMD-BCG"
PART_NUMBER"78.10421.2FL"
LOCATION"C25W49"
VALUE"SCD1U16V2KX-3GP";
"2"
$PN"2"5;
"1"
$PN"1"12;
%"P3V3_STBY"
"1","(-1100,1950)","0","mstr_symbols","I37";
;
CDS_LIB"mstr_symbols"
HDL_POWER"P3V3_STBY"
BODY_TYPE"PLUMBING"
SIZE"1B"
VOLTAGE"3.3V";
"G\NAC"11;
%"CAP"
"1","(-1900,2550)","0","mstr_discrete","I38";
;
CDS_SEC"1"
$SEC"1"
CDS_LOCATION"C25W48"
CDS_LIB"mstr_discrete"
BOM_COST"SM_CONTROLLER"
ROOM"BMC"
PACK_TYPE"0402"
TOLERANCE"10%"
LOCATION"C25W48"
MATERIAL"X6S"
VALUE"1.0UF"
VOLTAGE"6.3V"
PART_NUMBER"D97712-004";
"A"
$PN"1"12;
"B"
$PN"2"5;
%"HCB1608KF-800T30-GP"
"1","(-1900,3875)","1","w_hdl","I39";
;
CDS_SEC"1"
$SEC"1"
CDS_LOCATION"FB2T7"
CDS_LIB"w_hdl"
CDS_LMAN_SYM_OUTLINE"-50,100,50,-100"
PACK_TYPE"DISCRET-G9"
PART_NUMBER"68.00230.231"
VALUE"HCB1608KF-800T30-GP"
LOCATION"FB2T7";
"2"
$PN"2"32;
"1"
$PN"1"10;
%"CAP"
"1","(575,4900)","0","mstr_discrete","I4";
;
CDS_SEC"1"
$SEC"1"
CDS_LOCATION"C25W71"
ROOM"BMC"
BOM_COST"SM_CONTROLLER"
CDS_LIB"mstr_discrete"
PART_NUMBER"D97712-004"
PACK_TYPE"0402"
LOCATION"C25W71"
VALUE"1.0UF"
VOLTAGE"6.3V"
TOLERANCE"10%"
MATERIAL"X6S";
"A"
$PN"1"9;
"B"
$PN"2"18;
%"P3V3_STBY"
"1","(-2650,3050)","0","mstr_symbols","I40";
;
CDS_LIB"mstr_symbols"
HDL_POWER"P3V3_STBY"
BODY_TYPE"PLUMBING"
SIZE"1B"
VOLTAGE"3.3V";
"G\NAC"12;
%"P3V3_STBY"
"1","(-3025,5225)","0","mstr_symbols","I41";
;
SIZE"1B"
BODY_TYPE"PLUMBING"
HDL_POWER"P3V3_STBY"
CDS_LIB"mstr_symbols"
VOLTAGE"3.3V";
"G\NAC"13;
%"W_VCC_CIRCLE"
"1","(-3100,4025)","0","w_power","I42";
;
CDS_LIB"w_power"
CDS_LMAN_SYM_OUTLINE"-100,100,100,-100"
BODY_TYPE"PLUMBING"
HDL_POWER"VCC_DACAV3V3";
"VCC_CIRCLE \B"14;
%"SC4D7U10V3KX-GP"
"1","(-3675,4975)","0","w_hdl","I43";
;
CDS_SEC"1"
$SEC"1"
CDS_LOCATION"C25W30"
PART_NUMBER"78.47523.5BL"
PACK_TYPE"SMD-BCG"
CDS_LMAN_SYM_OUTLINE"-50,25,50,-25"
CDS_LIB"w_hdl"
LOCATION"C25W30"
VALUE"SC4D7U10V3KX-GP";
"2"
$PN"2"15;
"1"
$PN"1"27;
%"GND"
"1","(-3675,4500)","0","mstr_symbols","I44";
;
VOLTAGE"0.0V"
BODY_TYPE"PLUMBING"
HDL_POWER"GND"
SIZE"1B"
CDS_LIB"mstr_symbols";
"A\NAC"15;
%"CAP"
"1","(-4075,4975)","0","mstr_discrete","I45";
;
CDS_LOCATION"C25W29"
BOM_COST"SM_CONTROLLER"
ROOM"BMC"
SEC"1"
SEC_TYPE"0805"
CDS_SEC"1"
CDS_LIB"mstr_discrete"
VALUE"10UF"
TOLERANCE"10%"
PACK_TYPE"0805"
VOLTAGE"16V"
MATERIAL"X6S"
PART_NUMBER"C95333-007"
LOCATION"C25W29";
"A"
$PN"1"27;
"B"
$PN"2"15;
%"CAP"
"1","(-4475,4975)","0","mstr_discrete","I46";
;
CDS_SEC"1"
$SEC"1"
CDS_LOCATION"C25W28"
ROOM"BMC"
BOM_COST"SM_CONTROLLER"
CDS_LIB"mstr_discrete"
PART_NUMBER"D97712-004"
PACK_TYPE"0402"
MATERIAL"X6S"
TOLERANCE"10%"
VOLTAGE"6.3V"
VALUE"1.0UF"
LOCATION"C25W28";
"A"
$PN"1"27;
"B"
$PN"2"15;
%"P3V3_STBY"
"1","(-4400,4000)","0","mstr_symbols","I47";
;
SIZE"1B"
BODY_TYPE"PLUMBING"
HDL_POWER"P3V3_STBY"
CDS_LIB"mstr_symbols"
VOLTAGE"3.3V";
"G\NAC"16;
%"CAP"
"1","(-4875,4975)","0","mstr_discrete","I48";
;
CDS_SEC"1"
$SEC"1"
CDS_LOCATION"C25W27"
CDS_LIB"mstr_discrete"
BOM_COST"SM_CONTROLLER"
ROOM"BMC"
LOCATION"C25W27"
VOLTAGE"6.3V"
MATERIAL"X6S"
PACK_TYPE"0402"
TOLERANCE"10%"
PART_NUMBER"D97712-004"
VALUE"1.0UF";
"A"
$PN"1"27;
"B"
$PN"2"15;
%"W_VCC_CIRCLE"
"1","(-4900,4050)","0","w_power","I49";
;
CDS_LMAN_SYM_OUTLINE"-100,100,100,-100"
CDS_LIB"w_power"
BODY_TYPE"PLUMBING"
HDL_POWER"VCC_ADCAV3V3";
"VCC_CIRCLE \B"17;
%"GND"
"1","(575,4475)","0","mstr_symbols","I5";
;
CDS_LIB"mstr_symbols"
VOLTAGE"0.0V"
BODY_TYPE"PLUMBING"
SIZE"1B"
HDL_POWER"GND";
"A\NAC"18;
%"SC4D7U10V3KX-GP"
"1","(-3100,3600)","0","w_hdl","I50";
;
CDS_SEC"1"
$SEC"1"
CDS_LOCATION"C25W36"
PACK_TYPE"SMD-BCG"
PART_NUMBER"78.47523.5BL"
CDS_LMAN_SYM_OUTLINE"-50,25,50,-25"
CDS_LIB"w_hdl"
VALUE"SC4D7U10V3KX-GP"
LOCATION"C25W36";
"2"
$PN"2"19;
"1"
$PN"1"14;
%"CAP"
"1","(-3450,3600)","0","mstr_discrete","I51";
;
CDS_SEC"1"
$SEC"1"
CDS_LOCATION"C25W35"
CDS_LIB"mstr_discrete"
ROOM"BMC"
BOM_COST"SM_CONTROLLER"
PART_NUMBER"D97712-004"
LOCATION"C25W35"
PACK_TYPE"0402"
MATERIAL"X6S"
VALUE"1.0UF"
VOLTAGE"6.3V"
TOLERANCE"10%";
"A"
$PN"1"14;
"B"
$PN"2"19;
%"GND"
"1","(-3100,3050)","0","mstr_symbols","I52";
;
HDL_POWER"GND"
SIZE"1B"
CDS_LIB"mstr_symbols"
BODY_TYPE"PLUMBING"
VOLTAGE"0.0V";
"A\NAC"19;
%"SCD1U16V2KX-3GP"
"1","(-3800,3575)","0","w_hdl","I53";
;
CDS_SEC"1"
$SEC"1"
CDS_LOCATION"C25W34"
PACK_TYPE"SMD-BCG"
PART_NUMBER"78.10421.2FL"
CDS_LIB"w_hdl"
CDS_LMAN_SYM_OUTLINE"-50,25,50,-25"
LOCATION"C25W34"
VALUE"SCD1U16V2KX-3GP";
"2"
$PN"2"19;
"1"
$PN"1"14;
%"SC4D7U10V3KX-GP"
"1","(-3675,2500)","0","w_hdl","I54";
;
CDS_SEC"1"
$SEC"1"
CDS_LOCATION"C25W47"
PACK_TYPE"SMD-BCG"
PART_NUMBER"78.47523.5BL"
CDS_LIB"w_hdl"
CDS_LMAN_SYM_OUTLINE"-50,25,50,-25"
VALUE"SC4D7U10V3KX-GP"
LOCATION"C25W47";
"2"
$PN"2"20;
"1"
$PN"1"21;
%"CAP"
"1","(-3975,2475)","0","mstr_discrete","I55";
;
CDS_SEC"1"
$SEC"1"
CDS_LOCATION"C25W46"
CDS_LIB"mstr_discrete"
ROOM"BMC"
BOM_COST"SM_CONTROLLER"
LOCATION"C25W46"
VALUE"10UF"
MATERIAL"X6S"
PART_NUMBER"C95333-007"
PACK_TYPE"0805"
TOLERANCE"10%"
VOLTAGE"16V";
"A"
$PN"1"21;
"B"
$PN"2"20;
%"GND"
"1","(-3750,1975)","0","mstr_symbols","I56";
;
CDS_LIB"mstr_symbols"
HDL_POWER"GND"
SIZE"1B"
BODY_TYPE"PLUMBING"
VOLTAGE"0.0V";
"A\NAC"20;
%"0R3J-0-U-GP"
"1","(-4075,3850)","1","w_hdl","I57";
;
CDS_SEC"1"
$SEC"1"
CDS_LOCATION"R25W93"
CDS_LMAN_SYM_OUTLINE"-50,75,50,-75"
CDS_LIB"w_hdl"
PART_NUMBER"63.00000.00L"
PACK_TYPE"RCL_GP"
VALUE"0R3J-0-U-GP"
LOCATION"R25W93";
"2"
$PN"2"14;
"1"
$PN"1"16;
%"W_VCC_CIRCLE"
"1","(-4325,2925)","0","w_power","I58";
;
BODY_TYPE"PLUMBING"
CDS_LIB"w_power"
CDS_LMAN_SYM_OUTLINE"-100,100,100,-100"
HDL_POWER"VCC_D_3V3";
"VCC_CIRCLE \B"21;
%"CAP"
"1","(-4900,3700)","0","mstr_discrete","I59";
;
CDS_SEC"1"
$SEC"1"
CDS_LOCATION"C25W33"
BOM_COST"SM_CONTROLLER"
ROOM"BMC"
CDS_LIB"mstr_discrete"
VALUE"1.0UF"
LOCATION"C25W33"
PART_NUMBER"D97712-004"
TOLERANCE"10%"
PACK_TYPE"0402"
MATERIAL"X6S"
VOLTAGE"6.3V";
"A"
$PN"1"17;
"B"
$PN"2"22;
%"SC4D7U10V3KX-GP"
"1","(75,4875)","0","w_hdl","I6";
;
CDS_SEC"1"
$SEC"1"
CDS_LOCATION"C25W70"
CDS_LIB"w_hdl"
CDS_LMAN_SYM_OUTLINE"-50,25,50,-25"
PACK_TYPE"SMD-BCG"
PART_NUMBER"78.47523.5BL"
LOCATION"C25W70"
VALUE"SC4D7U10V3KX-GP";
"2"
$PN"2"18;
"1"
$PN"1"9;
%"GND"
"1","(-4900,3175)","0","mstr_symbols","I60";
;
HDL_POWER"GND"
SIZE"1B"
CDS_LIB"mstr_symbols"
BODY_TYPE"PLUMBING"
VOLTAGE"0.0V";
"A\NAC"22;
%"SCD1U16V2KX-3GP"
"1","(-4325,2500)","0","w_hdl","I61";
;
CDS_SEC"1"
$SEC"1"
CDS_LOCATION"C25W45"
PART_NUMBER"78.10421.2FL"
PACK_TYPE"SMD-BCG"
CDS_LIB"w_hdl"
CDS_LMAN_SYM_OUTLINE"-50,25,50,-25"
LOCATION"C25W45"
VALUE"SCD1U16V2KX-3GP";
"2"
$PN"2"20;
"1"
$PN"1"21;
%"CAP"
"1","(-4575,2475)","0","mstr_discrete","I62";
;
CDS_SEC"1"
$SEC"1"
CDS_LOCATION"C25W44"
CDS_LIB"mstr_discrete"
BOM_COST"SM_CONTROLLER"
ROOM"BMC"
VOLTAGE"6.3V"
VALUE"1.0UF"
LOCATION"C25W44"
TOLERANCE"10%"
MATERIAL"X6S"
PART_NUMBER"D97712-004"
PACK_TYPE"0402";
"A"
$PN"1"21;
"B"
$PN"2"20;
%"CAP"
"1","(-4875,2475)","0","mstr_discrete","I63";
;
CDS_SEC"1"
$SEC"1"
CDS_LOCATION"C25W43"
CDS_LIB"mstr_discrete"
BOM_COST"SM_CONTROLLER"
ROOM"BMC"
PACK_TYPE"0402"
PART_NUMBER"D97712-004"
VOLTAGE"6.3V"
LOCATION"C25W43"
VALUE"1.0UF"
TOLERANCE"10%"
MATERIAL"X6S";
"A"
$PN"1"21;
"B"
$PN"2"20;
%"W_VCC_CIRCLE"
"1","(-4775,1875)","0","w_power","I64";
;
BODY_TYPE"PLUMBING"
CDS_LMAN_SYM_OUTLINE"-100,100,100,-100"
CDS_LIB"w_power"
HDL_POWER"VCC_PA_3V3";
"VCC_CIRCLE \B"23;
%"SC4D7U10V3KX-GP"
"1","(-1800,1325)","0","w_hdl","I65";
;
CDS_SEC"1"
$SEC"1"
CDS_LOCATION"C25W62"
PACK_TYPE"SMD-BCG"
PART_NUMBER"78.47523.5BL"
CDS_LMAN_SYM_OUTLINE"-50,25,50,-25"
CDS_LIB"w_hdl"
VALUE"SC4D7U10V3KX-GP"
LOCATION"C25W62";
"2"
$PN"2"24;
"1"
$PN"1"25;
%"GND"
"1","(-1800,950)","0","mstr_symbols","I66";
;
SIZE"1B"
HDL_POWER"GND"
CDS_LIB"mstr_symbols"
BODY_TYPE"PLUMBING"
VOLTAGE"0.0V";
"A\NAC"24;
%"SCD1U16V2KX-3GP"
"1","(-2200,1325)","0","w_hdl","I67";
;
CDS_SEC"1"
$SEC"1"
CDS_LOCATION"C25W61"
PACK_TYPE"SMD-BCG"
PART_NUMBER"78.10421.2FL"
CDS_LMAN_SYM_OUTLINE"-50,25,50,-25"
CDS_LIB"w_hdl"
VALUE"SCD1U16V2KX-3GP"
LOCATION"C25W61";
"2"
$PN"2"24;
"1"
$PN"1"25;
%"P3V3_STBY"
"1","(-3500,1800)","0","mstr_symbols","I68";
;
HDL_POWER"P3V3_STBY"
BODY_TYPE"PLUMBING"
SIZE"1B"
CDS_LIB"mstr_symbols"
VOLTAGE"3.3V";
"G\NAC"25;
%"SC4D7U10V3KX-GP"
"1","(-4775,1400)","0","w_hdl","I69";
;
CDS_SEC"1"
$SEC"1"
CDS_LOCATION"C25W59"
PART_NUMBER"78.47523.5BL"
PACK_TYPE"SMD-BCG"
CDS_LMAN_SYM_OUTLINE"-50,25,50,-25"
CDS_LIB"w_hdl"
VALUE"SC4D7U10V3KX-GP"
LOCATION"C25W59";
"2"
$PN"2"26;
"1"
$PN"1"23;
%"0R3J-0-U-GP"
"1","(-100,5075)","1","w_hdl","I7";
;
CDS_SEC"1"
$SEC"1"
CDS_LOCATION"R25W120"
CDS_LIB"w_hdl"
CDS_LMAN_SYM_OUTLINE"-50,75,50,-75"
PART_NUMBER"63.00000.00L"
PACK_TYPE"RCL_GP"
LOCATION"R25W120"
VALUE"0R3J-0-U-GP";
"2"
$PN"2"9;
"1"
$PN"1"29;
%"GND"
"1","(-4775,925)","0","mstr_symbols","I70";
;
SIZE"1B"
HDL_POWER"GND"
CDS_LIB"mstr_symbols"
BODY_TYPE"PLUMBING"
VOLTAGE"0.0V";
"A\NAC"26;
%"CAP"
"1","(-5275,4975)","0","mstr_discrete","I71";
;
CDS_SEC"1"
$SEC"1"
CDS_LOCATION"C25W26"
CDS_LIB"mstr_discrete"
ROOM"BMC"
BOM_COST"SM_CONTROLLER"
LOCATION"C25W26"
TOLERANCE"10%"
PART_NUMBER"D97712-004"
PACK_TYPE"0402"
MATERIAL"X6S"
VOLTAGE"6.3V"
VALUE"1.0UF";
"A"
$PN"1"27;
"B"
$PN"2"15;
%"CAP"
"1","(-5675,4975)","0","mstr_discrete","I72";
;
CDS_LOCATION"C25W25"
CDS_LIB"mstr_discrete"
BOM_COST"SM_CONTROLLER"
ROOM"BMC"
SEC_TYPE"0402"
SEC"1"
CDS_SEC"1"
PART_NUMBER"D97712-004"
PACK_TYPE"0402"
MATERIAL"X6S"
TOLERANCE"10%"
VOLTAGE"6.3V"
VALUE"1.0UF"
LOCATION"C25W25";
"A"
$PN"1"27;
"B"
$PN"2"15;
%"CAP"
"1","(-6075,4975)","0","mstr_discrete","I73";
;
CDS_LOCATION"C25W24"
CDS_LIB"mstr_discrete"
ROOM"BMC"
BOM_COST"SM_CONTROLLER"
SEC_TYPE"0402"
SEC"1"
CDS_SEC"1"
PART_NUMBER"D97712-004"
PACK_TYPE"0402"
VALUE"1.0UF"
MATERIAL"X6S"
VOLTAGE"6.3V"
TOLERANCE"10%"
LOCATION"C25W24";
"A"
$PN"1"27;
"B"
$PN"2"15;
%"W_VCC_CIRCLE"
"1","(-6475,5200)","0","w_power","I74";
;
BODY_TYPE"PLUMBING"
CDS_LMAN_SYM_OUTLINE"-100,100,100,-100"
CDS_LIB"w_power"
HDL_POWER"P1V15_AUX_BMC";
"VCC_CIRCLE \B"27;
%"CAP"
"1","(-6475,4975)","0","mstr_discrete","I75";
;
CDS_LOCATION"C25W23"
ROOM"BMC"
CDS_LIB"mstr_discrete"
BOM_COST"SM_CONTROLLER"
SEC_TYPE"0402"
SEC"1"
CDS_SEC"1"
LOCATION"C25W23"
VALUE"1.0UF"
MATERIAL"X6S"
PACK_TYPE"0402"
PART_NUMBER"D97712-004"
VOLTAGE"6.3V"
TOLERANCE"10%";
"A"
$PN"1"27;
"B"
$PN"2"15;
%"HCB1608KF-800T30-GP"
"1","(-6300,3975)","1","w_hdl","I76";
;
CDS_SEC"1"
$SEC"1"
CDS_LOCATION"FB2T3"
CDS_LMAN_SYM_OUTLINE"-50,100,50,-100"
CDS_LIB"w_hdl"
PART_NUMBER"68.00230.231"
PACK_TYPE"DISCRET-G9"
LOCATION"FB2T3"
VALUE"HCB1608KF-800T30-GP";
"2"
$PN"2"17;
"1"
$PN"1"28;
%"P3V3_STBY"
"1","(-6575,4125)","0","mstr_symbols","I77";
;
VOLTAGE"3.3V"
CDS_LIB"mstr_symbols"
SIZE"1B"
BODY_TYPE"PLUMBING"
HDL_POWER"P3V3_STBY";
"G\NAC"28;
%"CAP"
"1","(-5250,3725)","0","mstr_discrete","I78";
;
CDS_SEC"1"
$SEC"1"
CDS_LOCATION"C25W32"
BOM_COST"SM_CONTROLLER"
ROOM"BMC"
CDS_LIB"mstr_discrete"
PART_NUMBER"D97712-004"
PACK_TYPE"0402"
MATERIAL"X6S"
TOLERANCE"10%"
VOLTAGE"6.3V"
VALUE"1.0UF"
LOCATION"C25W32";
"A"
$PN"1"17;
"B"
$PN"2"22;
%"SCD1U16V2KX-3GP"
"1","(-5700,3700)","0","w_hdl","I79";
;
CDS_SEC"1"
$SEC"1"
CDS_LOCATION"C25W31"
PART_NUMBER"78.10421.2FL"
PACK_TYPE"SMD-BCG"
CDS_LMAN_SYM_OUTLINE"-50,25,50,-25"
CDS_LIB"w_hdl"
LOCATION"C25W31"
VALUE"SCD1U16V2KX-3GP";
"2"
$PN"2"22;
"1"
$PN"1"17;
%"P3V3_STBY"
"1","(-425,5225)","0","mstr_symbols","I8";
;
CDS_LIB"mstr_symbols"
SIZE"1B"
BODY_TYPE"PLUMBING"
HDL_POWER"P3V3_STBY"
VOLTAGE"3.3V";
"G\NAC"29;
%"CAP"
"1","(-5125,2475)","0","mstr_discrete","I80";
;
CDS_SEC"1"
$SEC"1"
CDS_LOCATION"C25W42"
ROOM"BMC"
BOM_COST"SM_CONTROLLER"
CDS_LIB"mstr_discrete"
PART_NUMBER"D97712-004"
VOLTAGE"6.3V"
VALUE"1.0UF"
LOCATION"C25W42"
PACK_TYPE"0402"
MATERIAL"X6S"
TOLERANCE"10%";
"A"
$PN"1"21;
"B"
$PN"2"20;
%"CAP"
"1","(-5375,2475)","0","mstr_discrete","I81";
;
CDS_SEC"1"
$SEC"1"
CDS_LOCATION"C25W41"
ROOM"BMC"
BOM_COST"SM_CONTROLLER"
CDS_LIB"mstr_discrete"
VALUE"1.0UF"
VOLTAGE"6.3V"
PART_NUMBER"D97712-004"
LOCATION"C25W41"
TOLERANCE"10%"
MATERIAL"X6S"
PACK_TYPE"0402";
"A"
$PN"1"21;
"B"
$PN"2"20;
%"CAP"
"1","(-5675,2475)","0","mstr_discrete","I82";
;
CDS_SEC"1"
$SEC"1"
CDS_LOCATION"C25W40"
CDS_LIB"mstr_discrete"
ROOM"BMC"
BOM_COST"SM_CONTROLLER"
LOCATION"C25W40"
VALUE"1.0UF"
PART_NUMBER"D97712-004"
VOLTAGE"6.3V"
TOLERANCE"10%"
MATERIAL"X6S"
PACK_TYPE"0402";
"A"
$PN"1"21;
"B"
$PN"2"20;
%"P3V3_STBY"
"1","(-6550,2925)","0","mstr_symbols","I83";
;
VOLTAGE"3.3V"
CDS_LIB"mstr_symbols"
HDL_POWER"P3V3_STBY"
BODY_TYPE"PLUMBING"
SIZE"1B";
"G\NAC"30;
%"HCB1608KF-800T30-GP"
"1","(-6275,2775)","1","w_hdl","I84";
;
CDS_SEC"1"
$SEC"1"
CDS_LOCATION"FB2T4"
PART_NUMBER"68.00230.231"
PACK_TYPE"DISCRET-G9"
CDS_LMAN_SYM_OUTLINE"-50,100,50,-100"
CDS_LIB"w_hdl"
VALUE"HCB1608KF-800T30-GP"
LOCATION"FB2T4";
"2"
$PN"2"21;
"1"
$PN"1"30;
%"SCD1U16V2KX-3GP"
"1","(-5175,1400)","0","w_hdl","I85";
;
CDS_SEC"1"
$SEC"1"
CDS_LOCATION"C25W58"
PACK_TYPE"SMD-BCG"
PART_NUMBER"78.10421.2FL"
CDS_LMAN_SYM_OUTLINE"-50,25,50,-25"
CDS_LIB"w_hdl"
LOCATION"C25W58"
VALUE"SCD1U16V2KX-3GP";
"2"
$PN"2"26;
"1"
$PN"1"23;
%"CAP"
"1","(-5475,1375)","0","mstr_discrete","I86";
;
CDS_SEC"1"
$SEC"1"
CDS_LOCATION"C25W57"
BOM_COST"SM_CONTROLLER"
ROOM"BMC"
CDS_LIB"mstr_discrete"
PACK_TYPE"0402"
PART_NUMBER"D97712-004"
MATERIAL"X6S"
TOLERANCE"10%"
VOLTAGE"6.3V"
VALUE"1.0UF"
LOCATION"C25W57";
"A"
$PN"1"23;
"B"
$PN"2"26;
%"CAP"
"1","(-5725,1375)","0","mstr_discrete","I87";
;
CDS_SEC"1"
$SEC"1"
CDS_LOCATION"C25W56"
BOM_COST"SM_CONTROLLER"
ROOM"BMC"
CDS_LIB"mstr_discrete"
PACK_TYPE"0402"
TOLERANCE"10%"
PART_NUMBER"D97712-004"
LOCATION"C25W56"
VALUE"1.0UF"
VOLTAGE"6.3V"
MATERIAL"X6S";
"A"
$PN"1"23;
"B"
$PN"2"26;
%"P3V3_STBY"
"1","(-6550,1875)","0","mstr_symbols","I88";
;
VOLTAGE"3.3V"
CDS_LIB"mstr_symbols"
SIZE"1B"
BODY_TYPE"PLUMBING"
HDL_POWER"P3V3_STBY";
"G\NAC"31;
%"HCB1608KF-800T30-GP"
"1","(-6250,1725)","1","w_hdl","I89";
;
CDS_SEC"1"
$SEC"1"
CDS_LOCATION"FB2T5"
CDS_LMAN_SYM_OUTLINE"-50,100,50,-100"
CDS_LIB"w_hdl"
PACK_TYPE"DISCRET-G9"
PART_NUMBER"68.00230.231"
LOCATION"FB2T5"
VALUE"HCB1608KF-800T30-GP";
"2"
$PN"2"23;
"1"
$PN"1"31;
%"W_VCC_CIRCLE"
"1","(-500,4025)","0","w_power","I9";
;
BODY_TYPE"PLUMBING"
CDS_LIB"w_power"
CDS_LMAN_SYM_OUTLINE"-100,100,100,-100"
HDL_POWER"VCC_A_1V1";
"VCC_CIRCLE \B"32;
END.
